# S9S_MB_2U (Grand Teton) — schematic netlist excerpt (pin names and nets, part order shuffled) for the footprints in the layout excerpt that follows; sources: Cadence DE-HDL packaged netlist, KiCad conversion of 03242023_DA0F0TMBIJ0_F0T_Motherboard_J_brd_V01_OCP.brd

R1348  Q_RES  0 5% CHIP  pkg 0402LF  page 134 : A = JTAG_DBP_CPU_GTL_TCK_R1 ; B = JTAG_DBP_CPU_GTL_TCK

U215  MOSFET_N  BSS138K IC  pkg SMLF  page 164
  DRAIN  = HP_LVC3_OCP_V3_2_PRSNT2
  GATE  = HP_LVC3_OCP_V3_2_PRSNT2_N
  SOURCE  = GND

(kicad_pcb
	(version 20260206)
	(generator "pcbnew")
	(generator_version "10.0")
	(general
		(thickness 1.6)
		(legacy_teardrops no)
	)
	(paper "A4")
	(title_block
		(title "03242023_DA0F0TMBIJ0_F0T_Motherboard_J_brd_V01_OCP.brd")
		(comment 1 "Grand Teton / footprints 1899-1900 of 6105")
	)
	(layers
		(0 "F.Cu" signal "TOP")
		(4 "In1.Cu" signal "GND")
		(6 "In2.Cu" signal "IN1")
		(8 "In3.Cu" signal "GND1")
		(10 "In4.Cu" signal "IN2")
		(12 "In5.Cu" signal "GND2")
		(14 "In6.Cu" signal "IN3")
		(16 "In7.Cu" signal "GND3")
		(18 "In8.Cu" signal "VCC")
		(20 "In9.Cu" signal "VCC1")
		(22 "In10.Cu" signal "GND4")
		(24 "In11.Cu" signal "IN4")
		(26 "In12.Cu" signal "GND5")
		(28 "In13.Cu" signal "IN5")
		(30 "In14.Cu" signal "GND6")
		(32 "In15.Cu" signal "IN6")
		(34 "In16.Cu" signal "GND7")
		(2 "B.Cu" signal "BOTTOM")
		(9 "F.Adhes" user "F.Adhesive")
		(11 "B.Adhes" user "B.Adhesive")
		(13 "F.Paste" user "Package Geometry/Pastemask Top")
		(15 "B.Paste" user "Package Geometry/Pastemask Bottom")
		(5 "F.SilkS" user "Ref Des/Silkscreen Top")
		(7 "B.SilkS" user "Ref Des/Silkscreen Bottom")
		(1 "F.Mask" user "Board Geometry/Soldermask Top")
		(3 "B.Mask" user "Board Geometry/Soldermask Bottom")
		(17 "Dwgs.User" user "User.Drawings")
		(19 "Cmts.User" user "User.Comments")
		(21 "Eco1.User" user "User.Eco1")
		(23 "Eco2.User" user "User.Eco2")
		(25 "Edge.Cuts" user "Board Geometry/Outline")
		(27 "Margin" user)
		(31 "F.CrtYd" user "Package Geometry/Place Bound Top")
		(29 "B.CrtYd" user "Package Geometry/Place Bound Bottom")
		(35 "F.Fab" user "Ref Des/Assembly Top")
		(33 "B.Fab" user "Ref Des/Assembly Bottom")
	)
	(footprint ""
		(layer "F.Cu")
		(at 96.57588 -53.050948 180)
		(property "Reference" "R1348"
			(at 0 0 180)
			(layer "F.SilkS")
			(hide yes)
			(effects
				(font
					(size 1.27 1.27)
				)
			)
		)
		(property "Value" ""
			(at 0 0 180)
			(layer "F.Fab")
			(effects
				(font
					(size 1.27 1.27)
				)
			)
		)
		(duplicate_pad_numbers_are_jumpers no)
		(fp_line
			(start 0.7874 0.4064)
			(end -0.7874 0.4064)
			(stroke
				(width 0.1524)
				(type default)
			)
			(layer "F.SilkS")
		)
		(fp_line
			(start 0.7874 -0.4064)
			(end 0.7874 0.4064)
			(stroke
				(width 0.1524)
				(type default)
			)
			(layer "F.SilkS")
		)
		(fp_line
			(start -0.7874 0.4064)
			(end -0.7874 -0.4064)
			(stroke
				(width 0.1524)
				(type default)
			)
			(layer "F.SilkS")
		)
		(fp_line
			(start -0.7874 -0.4064)
			(end 0.7874 -0.4064)
			(stroke
				(width 0.1524)
				(type default)
			)
			(layer "F.SilkS")
		)
		(fp_line
			(start 0.67945 0.3048)
			(end 0.120396 0.3048)
			(stroke
				(width 0.1)
				(type default)
			)
			(layer "F.Fab")
		)
		(fp_line
			(start 0.67945 -0.3048)
			(end 0.67945 0.3048)
			(stroke
				(width 0.1)
				(type default)
			)
			(layer "F.Fab")
		)
		(fp_line
			(start 0.12065 -0.2794)
			(end 0.12065 -0.3048)
			(stroke
				(width 0.1)
				(type default)
			)
			(layer "F.Fab")
		)
		(fp_line
			(start 0.12065 -0.3048)
			(end 0.67945 -0.3048)
			(stroke
				(width 0.1)
				(type default)
			)
			(layer "F.Fab")
		)
		(fp_line
			(start 0.120396 0.3048)
			(end 0.120396 0.2794)
			(stroke
				(width 0.1)
				(type default)
			)
			(layer "F.Fab")
		)
		(fp_line
			(start 0.120396 0.2794)
			(end -0.12065 0.2794)
			(stroke
				(width 0.1)
				(type default)
			)
			(layer "F.Fab")
		)
		(fp_line
			(start -0.12065 0.3048)
			(end -0.67945 0.3048)
			(stroke
				(width 0.1)
				(type default)
			)
			(layer "F.Fab")
		)
		(fp_line
			(start -0.12065 0.2794)
			(end -0.12065 0.3048)
			(stroke
				(width 0.1)
				(type default)
			)
			(layer "F.Fab")
		)
		(fp_line
			(start -0.12065 -0.2794)
			(end 0.12065 -0.2794)
			(stroke
				(width 0.1)
				(type default)
			)
			(layer "F.Fab")
		)
		(fp_line
			(start -0.12065 -0.305054)
			(end -0.12065 -0.2794)
			(stroke
				(width 0.1)
				(type default)
			)
			(layer "F.Fab")
		)
		(fp_line
			(start -0.67945 0.3048)
			(end -0.67945 -0.305054)
			(stroke
				(width 0.1)
				(type default)
			)
			(layer "F.Fab")
		)
		(fp_line
			(start -0.67945 -0.305054)
			(end -0.12065 -0.305054)
			(stroke
				(width 0.1)
				(type default)
			)
			(layer "F.Fab")
		)
		(pad "1" smd circle
			(at -0.40005 0 180)
			(size 0 0)
			(layers "F.Cu" "F.Mask" "F.Paste")
			(net "JTAG_DBP_CPU_GTL_TCK_R1")
		)
		(pad "2" smd circle
			(at 0.40005 0 180)
			(size 0 0)
			(layers "F.Cu" "F.Mask" "F.Paste")
			(net "JTAG_DBP_CPU_GTL_TCK")
		)
	)
	(footprint ""
		(layer "F.Cu")
		(at 131.65074 -112.791748 180)
		(property "Reference" "U215"
			(at -0.04572 -2.506472 0)
			(unlocked yes)
			(layer "F.SilkS")
			(effects
				(font
					(size 0.7874 0.5842)
					(thickness 0.1524)
				)
			)
		)
		(property "Value" ""
			(at 0 0 180)
			(layer "F.Fab")
			(effects
				(font
					(size 1.27 1.27)
				)
			)
		)
		(duplicate_pad_numbers_are_jumpers no)
		(fp_line
			(start 1.949958 1.610106)
			(end -1.949958 1.610106)
			(stroke
				(width 0.1524)
				(type default)
			)
			(layer "F.SilkS")
		)
		(fp_line
			(start 1.949958 -1.560068)
			(end 1.949958 1.610106)
			(stroke
				(width 0.1524)
				(type default)
			)
			(layer "F.SilkS")
		)
		(fp_line
			(start -1.949958 1.610106)
			(end -1.949958 -1.610106)
			(stroke
				(width 0.1524)
				(type default)
			)
			(layer "F.SilkS")
		)
		(fp_line
			(start -1.949958 -1.610106)
			(end 1.949958 -1.610106)
			(stroke
				(width 0.1524)
				(type default)
			)
			(layer "F.SilkS")
		)
		(fp_line
			(start 0.750062 1.560068)
			(end -0.750062 1.560068)
			(stroke
				(width 0.1)
				(type default)
			)
			(layer "F.Fab")
		)
		(fp_line
			(start 0.750062 -1.560068)
			(end 0.750062 1.560068)
			(stroke
				(width 0.1)
				(type default)
			)
			(layer "F.Fab")
		)
		(fp_line
			(start -0.750062 1.560068)
			(end -0.750062 -1.560068)
			(stroke
				(width 0.1)
				(type default)
			)
			(layer "F.Fab")
		)
		(fp_line
			(start -0.750062 -1.560068)
			(end 0.750062 -1.560068)
			(stroke
				(width 0.1)
				(type default)
			)
			(layer "F.Fab")
		)
		(pad "D" smd rect
			(at 1.100074 0 90)
			(size 1.016 1.4224)
			(layers "F.Cu" "F.Mask" "F.Paste")
			(net "HP_LVC3_OCP_V3_2_PRSNT2")
		)
		(pad "G" smd rect
			(at -1.100074 -0.94996 90)
			(size 1.016 1.4224)
			(layers "F.Cu" "F.Mask" "F.Paste")
			(net "HP_LVC3_OCP_V3_2_PRSNT2_N")
		)
		(pad "S" smd rect
			(at -1.100074 0.94996 90)
			(size 1.016 1.4224)
			(layers "F.Cu" "F.Mask" "F.Paste")
			(net "GND")
		)
	)
)
